(kicad_pcb
	(version 20260206)
	(generator "pcbnew")
	(generator_version "10.0")
	(general
		(thickness 1.6)
		(legacy_teardrops no)
	)
	(paper "A4")
	(title_block
		(title "fcb — Lightning_FCB_BRD.brd")
		(comment 1 "Lightning (Wiwynn / Facebook NVMe JBOF) / footprints 119-125 of 495")
	)
	(layers
		(0 "F.Cu" signal "TOP")
		(4 "In1.Cu" signal "L2GND")
		(6 "In2.Cu" signal "L3VCC")
		(2 "B.Cu" signal "BOTTOM")
		(9 "F.Adhes" user "F.Adhesive")
		(11 "B.Adhes" user "B.Adhesive")
		(13 "F.Paste" user "Package Geometry/Pastemask Top")
		(15 "B.Paste" user "Package Geometry/Pastemask Bottom")
		(5 "F.SilkS" user "Ref Des/Silkscreen Top")
		(7 "B.SilkS" user "Ref Des/Silkscreen Bottom")
		(1 "F.Mask" user "Board Geometry/Soldermask Top")
		(3 "B.Mask" user "Board Geometry/Soldermask Bottom")
		(17 "Dwgs.User" user "User.Drawings")
		(19 "Cmts.User" user "User.Comments")
		(21 "Eco1.User" user "User.Eco1")
		(23 "Eco2.User" user "User.Eco2")
		(25 "Edge.Cuts" user "Board Geometry/Outline")
		(27 "Margin" user)
		(31 "F.CrtYd" user "Package Geometry/Place Bound Top")
		(29 "B.CrtYd" user "Package Geometry/Place Bound Bottom")
		(35 "F.Fab" user "Ref Des/Assembly Top")
		(33 "B.Fab" user "Ref Des/Assembly Bottom")
	)
	(footprint ""
		(layer "F.Cu")
		(at 24.500078 -450.44995 90)
		(property "Reference" "PAD1"
			(at 0 0 90)
			(layer "F.SilkS")
			(hide yes)
			(effects
				(font
					(size 1.27 1.27)
				)
			)
		)
		(property "Value" "PAD-1P-424137-2-OG-GP"
			(at -22.9743 -0.4572 90)
			(unlocked yes)
			(layer "F.Fab")
			(hide yes)
			(effects
				(font
					(size 1.016 1.016)
					(thickness 0.1524)
				)
			)
		)
		(property "Device Type" "PAD-1P-424137-2-OG"
			(at -22.9743 -1.9812 90)
			(unlocked yes)
			(layer "F.Fab")
			(hide yes)
			(effects
				(font
					(size 1.016 1.016)
					(thickness 0.1524)
				)
			)
		)
		(duplicate_pad_numbers_are_jumpers no)
		(fp_line
			(start 21.4503 -7.0993)
			(end 21.4503 7.0993)
			(stroke
				(width 0.1524)
				(type default)
			)
			(layer "F.SilkS")
		)
		(fp_line
			(start -21.4503 -7.0993)
			(end 21.4503 -7.0993)
			(stroke
				(width 0.1524)
				(type default)
			)
			(layer "F.SilkS")
		)
		(fp_line
			(start -0.075946 5.750052)
			(end -0.075946 7.0993)
			(stroke
				(width 0.1524)
				(type default)
			)
			(layer "F.SilkS")
		)
		(fp_line
			(start 21.4503 7.0993)
			(end 2.816098 7.0993)
			(stroke
				(width 0.1524)
				(type default)
			)
			(layer "F.SilkS")
		)
		(fp_line
			(start 2.816098 7.0993)
			(end 2.816098 5.750052)
			(stroke
				(width 0.1524)
				(type default)
			)
			(layer "F.SilkS")
		)
		(fp_line
			(start -0.075946 7.0993)
			(end -21.4503 7.0993)
			(stroke
				(width 0.1524)
				(type default)
			)
			(layer "F.SilkS")
		)
		(fp_line
			(start -21.4503 7.0993)
			(end -21.4503 -7.0993)
			(stroke
				(width 0.1524)
				(type default)
			)
			(layer "F.SilkS")
		)
		(fp_arc
			(start -0.075946 5.750052)
			(mid 1.37008 4.304026)
			(end 2.816098 5.750052)
			(stroke
				(width 0.1524)
				(type default)
			)
			(layer "F.SilkS")
		)
		(fp_poly
			(pts
				(xy -21.7043 7.3533) (xy -21.7043 -7.3533) (xy 21.7043 -7.3533) (xy 21.7043 7.3533) (xy 2.562098 7.3533)
				(arc
					(start 2.562098 5.750052)
					(mid 1.370076 4.55803)
					(end 0.178054 5.750052)
				)
				(xy 0.178054 7.3533)
			)
			(stroke
				(width 0)
				(type default)
			)
			(fill no)
			(layer "F.CrtYd")
		)
		(fp_poly
			(pts
				(xy -21.7043 7.3533) (xy -21.7043 -7.3533) (xy 21.7043 -7.3533) (xy 21.7043 7.3533) (xy 2.562098 7.3533)
				(arc
					(start 2.562098 5.750052)
					(mid 1.370076 4.55803)
					(end 0.178054 5.750052)
				)
				(xy 0.178054 7.3533)
			)
			(stroke
				(width 0)
				(type default)
			)
			(fill no)
			(layer "F.Fab")
		)
		(pad "1" smd custom
			(at 0 0 90)
			(size 3.425063 3.425063)
			(layers "F.Cu" "F.Mask" "F.Paste")
			(net "P12V_AUX")
			(options
				(clearance outline)
				(anchor circle)
			)
			(primitives
				(gr_poly
					(pts
						(xy -0.329946 6.850126) (xy -21.20011 6.850126) (xy -21.20011 -6.850126) (xy 21.20011 -6.850126)
						(xy 21.20011 6.850126) (xy 3.070098 6.850126)
						(arc
							(start 3.070098 5.750052)
							(mid 1.370076 4.05003)
							(end -0.329946 5.750052)
						)
					)
					(width 0)
					(fill yes)
				)
			)
		)
	)
	(footprint ""
		(layer "F.Cu")
		(at 8.0518 -144.9832 -90)
		(property "Reference" "R64"
			(at 0 0 270)
			(layer "F.SilkS")
			(hide yes)
			(effects
				(font
					(size 1.27 1.27)
				)
			)
		)
		(property "Value" "4K7R2F-GP"
			(at 0.064008 -3.993896 270)
			(unlocked yes)
			(layer "F.Fab")
			(hide yes)
			(effects
				(font
					(size 1.016 1.016)
					(thickness 0.1524)
				)
			)
		)
		(property "Device Type" "R402H16"
			(at 0.064008 -5.517896 270)
			(unlocked yes)
			(layer "F.Fab")
			(hide yes)
			(effects
				(font
					(size 1.016 1.016)
					(thickness 0.1524)
				)
			)
		)
		(duplicate_pad_numbers_are_jumpers no)
		(fp_line
			(start -0.508 -0.9398)
			(end -0.508 0.9398)
			(stroke
				(width 0.1524)
				(type default)
			)
			(layer "F.SilkS")
		)
		(fp_line
			(start 0.508 -0.9398)
			(end -0.508 -0.9398)
			(stroke
				(width 0.1524)
				(type default)
			)
			(layer "F.SilkS")
		)
		(fp_rect
			(start -0.508 0.9398)
			(end 0.508 -0.9398)
			(stroke
				(width 0)
				(type default)
			)
			(fill no)
			(layer "F.CrtYd")
		)
		(fp_rect
			(start -0.508 0.9398)
			(end 0.508 -0.9398)
			(stroke
				(width 0)
				(type default)
			)
			(fill no)
			(layer "F.Fab")
		)
		(pad "1" smd custom
			(at 0 -0.4445 270)
			(size 0.1397 0.1397)
			(layers "F.Cu" "F.Mask" "F.Paste")
			(net "P12V")
			(options
				(clearance outline)
				(anchor circle)
			)
			(primitives
				(gr_poly
					(pts
						(arc
							(start -0.1778 -0.2794)
							(mid -0.249642 -0.249642)
							(end -0.2794 -0.1778)
						)
						(arc
							(start -0.2794 0.1778)
							(mid -0.249642 0.249642)
							(end -0.1778 0.2794)
						)
						(arc
							(start 0.1778 0.2794)
							(mid 0.249642 0.249642)
							(end 0.2794 0.1778)
						)
						(arc
							(start 0.2794 -0.1778)
							(mid 0.249642 -0.249642)
							(end 0.1778 -0.2794)
						)
					)
					(width 0)
					(fill yes)
				)
			)
		)
		(pad "2" smd custom
			(at 0 0.4445 270)
			(size 0.1397 0.1397)
			(layers "F.Cu" "F.Mask" "F.Paste")
			(net "PWM_OUT_FAN5_NET")
			(options
				(clearance outline)
				(anchor circle)
			)
			(primitives
				(gr_poly
					(pts
						(arc
							(start -0.1778 -0.2794)
							(mid -0.249642 -0.249642)
							(end -0.2794 -0.1778)
						)
						(arc
							(start -0.2794 0.1778)
							(mid -0.249642 0.249642)
							(end -0.1778 0.2794)
						)
						(arc
							(start 0.1778 0.2794)
							(mid 0.249642 0.249642)
							(end 0.2794 0.1778)
						)
						(arc
							(start 0.2794 -0.1778)
							(mid 0.249642 -0.249642)
							(end 0.1778 -0.2794)
						)
					)
					(width 0)
					(fill yes)
				)
			)
		)
	)
	(footprint ""
		(layer "F.Cu")
		(at 39.0652 -361.5436 90)
		(property "Reference" "PR46"
			(at 0 0 90)
			(layer "F.SilkS")
			(hide yes)
			(effects
				(font
					(size 1.27 1.27)
				)
			)
		)
		(property "Value" "51KR2F-L-GP"
			(at 0.064008 -3.993896 90)
			(unlocked yes)
			(layer "F.Fab")
			(hide yes)
			(effects
				(font
					(size 1.016 1.016)
					(thickness 0.1524)
				)
			)
		)
		(property "Device Type" "R402H16"
			(at 0.064008 -5.517896 90)
			(unlocked yes)
			(layer "F.Fab")
			(hide yes)
			(effects
				(font
					(size 1.016 1.016)
					(thickness 0.1524)
				)
			)
		)
		(duplicate_pad_numbers_are_jumpers no)
		(fp_line
			(start 0.508 -0.9398)
			(end -0.508 -0.9398)
			(stroke
				(width 0.1524)
				(type default)
			)
			(layer "F.SilkS")
		)
		(fp_line
			(start -0.508 -0.9398)
			(end -0.508 0.9398)
			(stroke
				(width 0.1524)
				(type default)
			)
			(layer "F.SilkS")
		)
		(fp_rect
			(start -0.508 0.9398)
			(end 0.508 -0.9398)
			(stroke
				(width 0)
				(type default)
			)
			(fill no)
			(layer "F.CrtYd")
		)
		(fp_rect
			(start -0.508 0.9398)
			(end 0.508 -0.9398)
			(stroke
				(width 0)
				(type default)
			)
			(fill no)
			(layer "F.Fab")
		)
		(pad "1" smd custom
			(at 0 -0.4445 90)
			(size 0.1397 0.1397)
			(layers "F.Cu" "F.Mask" "F.Paste")
			(net "P12V_AUX")
			(options
				(clearance outline)
				(anchor circle)
			)
			(primitives
				(gr_poly
					(pts
						(arc
							(start -0.1778 -0.2794)
							(mid -0.249642 -0.249642)
							(end -0.2794 -0.1778)
						)
						(arc
							(start -0.2794 0.1778)
							(mid -0.249642 0.249642)
							(end -0.1778 0.2794)
						)
						(arc
							(start 0.1778 0.2794)
							(mid 0.249642 0.249642)
							(end 0.2794 0.1778)
						)
						(arc
							(start 0.2794 -0.1778)
							(mid 0.249642 -0.249642)
							(end 0.1778 -0.2794)
						)
					)
					(width 0)
					(fill yes)
				)
			)
		)
		(pad "2" smd custom
			(at 0 0.4445 90)
			(size 0.1397 0.1397)
			(layers "F.Cu" "F.Mask" "F.Paste")
			(net "TEMP_ALM#_JP_1")
			(options
				(clearance outline)
				(anchor circle)
			)
			(primitives
				(gr_poly
					(pts
						(arc
							(start -0.1778 -0.2794)
							(mid -0.249642 -0.249642)
							(end -0.2794 -0.1778)
						)
						(arc
							(start -0.2794 0.1778)
							(mid -0.249642 0.249642)
							(end -0.1778 0.2794)
						)
						(arc
							(start 0.1778 0.2794)
							(mid 0.249642 0.249642)
							(end 0.2794 0.1778)
						)
						(arc
							(start 0.2794 -0.1778)
							(mid 0.249642 -0.249642)
							(end 0.1778 -0.2794)
						)
					)
					(width 0)
					(fill yes)
				)
			)
		)
	)
	(footprint ""
		(layer "F.Cu")
		(at 36.63569 -165.513766 180)
		(property "Reference" "R1"
			(at 0 0 180)
			(layer "F.SilkS")
			(hide yes)
			(effects
				(font
					(size 1.27 1.27)
				)
			)
		)
		(property "Value" "0R2J-2-GP"
			(at 0.064008 -3.993896 180)
			(unlocked yes)
			(layer "F.Fab")
			(hide yes)
			(effects
				(font
					(size 1.016 1.016)
					(thickness 0.1524)
				)
			)
		)
		(property "Device Type" "R402H16"
			(at 0.064008 -5.517896 180)
			(unlocked yes)
			(layer "F.Fab")
			(hide yes)
			(effects
				(font
					(size 1.016 1.016)
					(thickness 0.1524)
				)
			)
		)
		(duplicate_pad_numbers_are_jumpers no)
		(fp_line
			(start 0.508 -0.9398)
			(end -0.508 -0.9398)
			(stroke
				(width 0.1524)
				(type default)
			)
			(layer "F.SilkS")
		)
		(fp_line
			(start -0.508 -0.9398)
			(end -0.508 0.9398)
			(stroke
				(width 0.1524)
				(type default)
			)
			(layer "F.SilkS")
		)
		(fp_rect
			(start -0.508 0.9398)
			(end 0.508 -0.9398)
			(stroke
				(width 0)
				(type default)
			)
			(fill no)
			(layer "F.CrtYd")
		)
		(fp_rect
			(start -0.508 0.9398)
			(end 0.508 -0.9398)
			(stroke
				(width 0)
				(type default)
			)
			(fill no)
			(layer "F.Fab")
		)
		(pad "1" smd custom
			(at 0 -0.4445 180)
			(size 0.1397 0.1397)
			(layers "F.Cu" "F.Mask" "F.Paste")
			(net "I2C_C_SDA_NCT7904")
			(options
				(clearance outline)
				(anchor circle)
			)
			(primitives
				(gr_poly
					(pts
						(arc
							(start -0.1778 -0.2794)
							(mid -0.249642 -0.249642)
							(end -0.2794 -0.1778)
						)
						(arc
							(start -0.2794 0.1778)
							(mid -0.249642 0.249642)
							(end -0.1778 0.2794)
						)
						(arc
							(start 0.1778 0.2794)
							(mid 0.249642 0.249642)
							(end 0.2794 0.1778)
						)
						(arc
							(start 0.2794 -0.1778)
							(mid 0.249642 -0.249642)
							(end 0.1778 -0.2794)
						)
					)
					(width 0)
					(fill yes)
				)
			)
		)
		(pad "2" smd custom
			(at 0 0.4445 180)
			(size 0.1397 0.1397)
			(layers "F.Cu" "F.Mask" "F.Paste")
			(net "I2C_C_SDA")
			(options
				(clearance outline)
				(anchor circle)
			)
			(primitives
				(gr_poly
					(pts
						(arc
							(start -0.1778 -0.2794)
							(mid -0.249642 -0.249642)
							(end -0.2794 -0.1778)
						)
						(arc
							(start -0.2794 0.1778)
							(mid -0.249642 0.249642)
							(end -0.1778 0.2794)
						)
						(arc
							(start 0.1778 0.2794)
							(mid 0.249642 0.249642)
							(end 0.2794 0.1778)
						)
						(arc
							(start 0.2794 -0.1778)
							(mid 0.249642 -0.249642)
							(end 0.1778 -0.2794)
						)
					)
					(width 0)
					(fill yes)
				)
			)
		)
	)
	(footprint ""
		(layer "F.Cu")
		(at 16.9672 -256.9972 90)
		(property "Reference" "D7"
			(at 0 0 90)
			(layer "F.SilkS")
			(hide yes)
			(effects
				(font
					(size 1.27 1.27)
				)
			)
		)
		(property "Value" "BAS16H-GP"
			(at 0 -5.5372 90)
			(unlocked yes)
			(layer "F.Fab")
			(hide yes)
			(effects
				(font
					(size 1.016 1.016)
					(thickness 0.1524)
				)
			)
		)
		(property "Device Type" "SOD123AKH48"
			(at 0 -7.0612 90)
			(unlocked yes)
			(layer "F.Fab")
			(hide yes)
			(effects
				(font
					(size 1.016 1.016)
					(thickness 0.1524)
				)
			)
		)
		(duplicate_pad_numbers_are_jumpers no)
		(fp_line
			(start 1.016 -2.667)
			(end -1.016 -2.667)
			(stroke
				(width 0.1524)
				(type default)
			)
			(layer "F.SilkS")
		)
		(fp_line
			(start -1.016 -2.667)
			(end -1.016 2.667)
			(stroke
				(width 0.1524)
				(type default)
			)
			(layer "F.SilkS")
		)
		(fp_line
			(start 1.016 2.667)
			(end 1.016 -2.667)
			(stroke
				(width 0.1524)
				(type default)
			)
			(layer "F.SilkS")
		)
		(fp_line
			(start -1.016 2.667)
			(end 1.016 2.667)
			(stroke
				(width 0.1524)
				(type default)
			)
			(layer "F.SilkS")
		)
		(fp_line
			(start 0.889 2.921)
			(end -0.889 2.921)
			(stroke
				(width 0.508)
				(type default)
			)
			(layer "F.SilkS")
		)
		(fp_rect
			(start -1.143 3.175)
			(end 1.143 -2.794)
			(stroke
				(width 0)
				(type default)
			)
			(fill no)
			(layer "F.CrtYd")
		)
		(fp_poly
			(pts
				(xy -1.143 -2.794) (xy 1.143 -2.794) (xy 1.143 3.175) (xy -1.143 3.175)
			)
			(stroke
				(width 0)
				(type default)
			)
			(fill no)
			(layer "F.Fab")
		)
		(pad "A" smd rect
			(at 0 -1.6891 90)
			(size 0.889 1.397)
			(layers "F.Cu" "F.Mask" "F.Paste")
			(net "FAN_TACH5")
		)
		(pad "K" smd rect
			(at 0 1.6891 90)
			(size 0.889 1.397)
			(layers "F.Cu" "F.Mask" "F.Paste")
			(net "P12V")
		)
	)
	(footprint ""
		(layer "F.Cu")
		(at 31.36011 -171.677076)
		(property "Reference" "C11"
			(at 0 0 0)
			(layer "F.SilkS")
			(hide yes)
			(effects
				(font
					(size 1.27 1.27)
				)
			)
		)
		(property "Value" "SCD1U50V3KX-GP"
			(at 0 -2.8194 0)
			(unlocked yes)
			(layer "F.Fab")
			(hide yes)
			(effects
				(font
					(size 1.016 1.016)
					(thickness 0.1524)
				)
			)
		)
		(property "Device Type" "C603H36"
			(at 0 -4.3434 0)
			(unlocked yes)
			(layer "F.Fab")
			(hide yes)
			(effects
				(font
					(size 1.016 1.016)
					(thickness 0.1524)
				)
			)
		)
		(duplicate_pad_numbers_are_jumpers no)
		(fp_line
			(start 0.508 0)
			(end -0.508 0)
			(stroke
				(width 0.2032)
				(type default)
			)
			(layer "F.SilkS")
		)
		(fp_rect
			(start -0.5842 1.3335)
			(end 0.5842 -1.3335)
			(stroke
				(width 0)
				(type default)
			)
			(fill no)
			(layer "F.CrtYd")
		)
		(fp_rect
			(start -0.5842 1.3335)
			(end 0.5842 -1.3335)
			(stroke
				(width 0)
				(type default)
			)
			(fill no)
			(layer "F.Fab")
		)
		(pad "1" smd custom
			(at 0 -0.762)
			(size 0.2159 0.2159)
			(layers "F.Cu" "F.Mask" "F.Paste")
			(net "P3V3")
			(options
				(clearance outline)
				(anchor circle)
			)
			(primitives
				(gr_poly
					(pts
						(arc
							(start -0.3302 -0.4318)
							(mid -0.402042 -0.402042)
							(end -0.4318 -0.3302)
						)
						(arc
							(start -0.4318 0.3302)
							(mid -0.402042 0.402042)
							(end -0.3302 0.4318)
						)
						(arc
							(start 0.3302 0.4318)
							(mid 0.402042 0.402042)
							(end 0.4318 0.3302)
						)
						(arc
							(start 0.4318 -0.3302)
							(mid 0.402042 -0.402042)
							(end 0.3302 -0.4318)
						)
					)
					(width 0)
					(fill yes)
				)
			)
		)
		(pad "2" smd custom
			(at 0 0.762)
			(size 0.2159 0.2159)
			(layers "F.Cu" "F.Mask" "F.Paste")
			(net "GND")
			(options
				(clearance outline)
				(anchor circle)
			)
			(primitives
				(gr_poly
					(pts
						(arc
							(start -0.3302 -0.4318)
							(mid -0.402042 -0.402042)
							(end -0.4318 -0.3302)
						)
						(arc
							(start -0.4318 0.3302)
							(mid -0.402042 0.402042)
							(end -0.3302 0.4318)
						)
						(arc
							(start 0.3302 0.4318)
							(mid 0.402042 0.402042)
							(end 0.4318 0.3302)
						)
						(arc
							(start 0.4318 -0.3302)
							(mid 0.402042 -0.402042)
							(end 0.3302 -0.4318)
						)
					)
					(width 0)
					(fill yes)
				)
			)
		)
	)
	(footprint ""
		(layer "F.Cu")
		(at 23.749 -106.426 90)
		(property "Reference" "TC3"
			(at 0 0 90)
			(layer "F.SilkS")
			(hide yes)
			(effects
				(font
					(size 1.27 1.27)
				)
			)
		)
		(property "Value" "ST68U16VDM-1-GP"
			(at 0 -9.6012 90)
			(unlocked yes)
			(layer "F.Fab")
			(hide yes)
			(effects
				(font
					(size 1.016 1.016)
					(thickness 0.1524)
				)
			)
		)
		(property "Device Type" "CT7343H79"
			(at 0 -11.1252 90)
			(unlocked yes)
			(layer "F.Fab")
			(hide yes)
			(effects
				(font
					(size 1.016 1.016)
					(thickness 0.1524)
				)
			)
		)
		(duplicate_pad_numbers_are_jumpers no)
		(fp_line
			(start 2.286 -4.8768)
			(end -2.286 -4.8768)
			(stroke
				(width 0.1524)
				(type default)
			)
			(layer "F.SilkS")
		)
		(fp_line
			(start -2.286 -4.8768)
			(end -2.286 -2.032)
			(stroke
				(width 0.1524)
				(type default)
			)
			(layer "F.SilkS")
		)
		(fp_line
			(start 2.1082 -4.699)
			(end -2.1082 -4.699)
			(stroke
				(width 0.508)
				(type default)
			)
			(layer "F.SilkS")
		)
		(fp_line
			(start 2.286 -2.032)
			(end 2.286 -4.8768)
			(stroke
				(width 0.1524)
				(type default)
			)
			(layer "F.SilkS")
		)
		(fp_line
			(start 2.286 2.032)
			(end 2.286 4.8768)
			(stroke
				(width 0.1524)
				(type default)
			)
			(layer "F.SilkS")
		)
		(fp_line
			(start 2.286 4.8768)
			(end -2.286 4.8768)
			(stroke
				(width 0.1524)
				(type default)
			)
			(layer "F.SilkS")
		)
		(fp_line
			(start -2.286 4.8768)
			(end -2.286 2.032)
			(stroke
				(width 0.1524)
				(type default)
			)
			(layer "F.SilkS")
		)
		(fp_rect
			(start -2.1463 3.6449)
			(end 2.1463 -3.6449)
			(stroke
				(width 0)
				(type default)
			)
			(fill no)
			(layer "F.CrtYd")
		)
		(fp_poly
			(pts
				(xy -2.54 4.953) (xy -2.54 4.2926) (xy -3.81 4.2926) (xy -3.81 -4.2926) (xy -2.54 -4.2926) (xy -2.54 -4.953)
				(xy 2.54 -4.953) (xy 2.54 -4.2926) (xy 3.81 -4.2926) (xy 3.81 -1.6256) (xy 2.1463 -1.6256) (xy 2.1463 -3.6449)
				(xy -2.1463 -3.6449) (xy -2.1463 3.6449) (xy 2.1463 3.6449) (xy 2.1463 -1.6129) (xy 3.81 -1.6129)
				(xy 3.81 4.2926) (xy 2.54 4.2926) (xy 2.54 4.953)
			)
			(stroke
				(width 0)
				(type default)
			)
			(fill no)
			(layer "F.CrtYd")
		)
		(fp_rect
			(start 2.54 4.2926)
			(end 3.81 -4.2926)
			(stroke
				(width 0)
				(type default)
			)
			(fill no)
			(layer "F.Fab")
		)
		(fp_rect
			(start -3.81 4.2926)
			(end -2.54 -4.2926)
			(stroke
				(width 0)
				(type default)
			)
			(fill no)
			(layer "F.Fab")
		)
		(fp_rect
			(start -2.54 4.953)
			(end 2.54 -4.953)
			(stroke
				(width 0)
				(type default)
			)
			(fill no)
			(layer "F.Fab")
		)
		(pad "1" smd rect
			(at 0 -3.1496 90)
			(size 2.413 2.286)
			(layers "F.Cu" "F.Mask" "F.Paste")
			(net "P12VU")
		)
		(pad "2" smd rect
			(at 0 3.1496 90)
			(size 2.413 2.286)
			(layers "F.Cu" "F.Mask" "F.Paste")
			(net "GND")
		)
		(zone
			(layer "F.Cu")
			(hatch none 0.5)
			(connect_pads
				(clearance 0)
			)
			(min_thickness 0.25)
			(keepout
				(tracks allowed)
				(vias not_allowed)
				(pads allowed)
				(copperpour not_allowed)
				(footprints allowed)
			)
			(placement
				(enabled no)
				(sheetname "")
			)
			(fill
				(thermal_gap 0.5)
				(thermal_bridge_width 0.5)
				(island_removal_mode 0)
			)
			(polygon
				(pts
					(xy 22.0599 -107.9373) (xy 19.1516 -107.9373) (xy 19.1516 -104.9147) (xy 22.0472 -104.9147) (xy 22.3774 -104.9147)
					(xy 22.3774 -107.9373)
				)
			)
		)
		(zone
			(layer "F.Cu")
			(hatch none 0.5)
			(connect_pads
				(clearance 0)
			)
			(min_thickness 0.25)
			(keepout
				(tracks allowed)
				(vias not_allowed)
				(pads allowed)
				(copperpour not_allowed)
				(footprints allowed)
			)
			(placement
				(enabled no)
				(sheetname "")
			)
			(fill
				(thermal_gap 0.5)
				(thermal_bridge_width 0.5)
				(island_removal_mode 0)
			)
			(polygon
				(pts
					(xy 28.3464 -104.9147) (xy 28.3464 -107.9373) (xy 25.4508 -107.9373) (xy 25.1206 -107.9373) (xy 25.1206 -104.9147)
					(xy 25.4508 -104.9147)
				)
			)
		)
	)
)
